(kicad_pcb
	(version 20260206)
	(generator "pcbnew")
	(generator_version "10.0")
	(general
		(thickness 1.6)
		(legacy_teardrops no)
	)
	(paper "A4")
	(title_block
		(title "Wiwynn_Tioga_Pass_MB.brd")
		(comment 1 "Tioga Pass / footprints 2947-2953 of 4770")
	)
	(layers
		(0 "F.Cu" signal "TOP")
		(4 "In1.Cu" signal "L2GND")
		(6 "In2.Cu" signal "L3")
		(8 "In3.Cu" signal "L4GND")
		(10 "In4.Cu" signal "L5")
		(12 "In5.Cu" signal "L6GND")
		(14 "In6.Cu" signal "L7VCC")
		(16 "In7.Cu" signal "L8VCC")
		(18 "In8.Cu" signal "L9GND")
		(20 "In9.Cu" signal "L10")
		(22 "In10.Cu" signal "L11GND")
		(24 "In11.Cu" signal "L12")
		(26 "In12.Cu" signal "L13GND")
		(2 "B.Cu" signal "BOTTOM")
		(9 "F.Adhes" user "F.Adhesive")
		(11 "B.Adhes" user "B.Adhesive")
		(13 "F.Paste" user "Package Geometry/Pastemask Top")
		(15 "B.Paste" user "Package Geometry/Pastemask Bottom")
		(5 "F.SilkS" user "Ref Des/Silkscreen Top")
		(7 "B.SilkS" user "Ref Des/Silkscreen Bottom")
		(1 "F.Mask" user "Board Geometry/Soldermask Top")
		(3 "B.Mask" user "Board Geometry/Soldermask Bottom")
		(17 "Dwgs.User" user "User.Drawings")
		(19 "Cmts.User" user "User.Comments")
		(21 "Eco1.User" user "User.Eco1")
		(23 "Eco2.User" user "User.Eco2")
		(25 "Edge.Cuts" user "Board Geometry/Outline")
		(27 "Margin" user)
		(31 "F.CrtYd" user "Package Geometry/Place Bound Top")
		(29 "B.CrtYd" user "Package Geometry/Place Bound Bottom")
		(35 "F.Fab" user "Ref Des/Assembly Top")
		(33 "B.Fab" user "Ref Des/Assembly Bottom")
	)
	(footprint ""
		(layer "B.Cu")
		(at 265.672824 -85.075014)
		(property "Reference" "C5P2"
			(at 0 0 0)
			(layer "B.SilkS")
			(hide yes)
			(effects
				(font
					(size 1.27 1.27)
				)
				(justify mirror)
			)
		)
		(property "Value" ""
			(at 0 0 0)
			(layer "B.Fab")
			(effects
				(font
					(size 1.27 1.27)
				)
				(justify mirror)
			)
		)
		(duplicate_pad_numbers_are_jumpers no)
		(fp_poly
			(pts
				(xy 0.7239 -0.2159) (xy -0.7239 -0.2159) (xy -0.7239 1.9939) (xy 0.7239 1.9939)
			)
			(stroke
				(width 0)
				(type default)
			)
			(fill no)
			(layer "B.CrtYd")
		)
		(fp_line
			(start -0.7239 -0.2159)
			(end 0.7239 -0.2159)
			(stroke
				(width 0.1)
				(type default)
			)
			(layer "B.Fab")
		)
		(fp_line
			(start -0.7239 1.9939)
			(end -0.7239 -0.2159)
			(stroke
				(width 0.1)
				(type default)
			)
			(layer "B.Fab")
		)
		(fp_line
			(start 0.7239 -0.2159)
			(end 0.7239 1.9939)
			(stroke
				(width 0.1)
				(type default)
			)
			(layer "B.Fab")
		)
		(fp_line
			(start 0.7239 1.9939)
			(end -0.7239 1.9939)
			(stroke
				(width 0.1)
				(type default)
			)
			(layer "B.Fab")
		)
		(pad "1" smd rect
			(at 0 0 180)
			(size 1.27 1.016)
			(layers "B.Cu" "B.Mask" "B.Paste")
			(net "PVDDQ_DEF")
		)
		(pad "2" smd rect
			(at 0 1.778 180)
			(size 1.27 1.016)
			(layers "B.Cu" "B.Mask" "B.Paste")
			(net "GND")
		)
		(zone
			(layer "B.Cu")
			(hatch none 0.5)
			(connect_pads
				(clearance 0)
			)
			(min_thickness 0.25)
			(keepout
				(tracks not_allowed)
				(vias allowed)
				(pads allowed)
				(copperpour not_allowed)
				(footprints allowed)
			)
			(placement
				(enabled no)
				(sheetname "")
			)
			(fill
				(thermal_gap 0.5)
				(thermal_bridge_width 0.5)
				(island_removal_mode 0)
			)
			(polygon
				(pts
					(xy 266.307824 -84.567014) (xy 265.037824 -84.567014) (xy 265.037824 -83.805014) (xy 266.307824 -83.805014)
				)
			)
		)
	)
	(footprint ""
		(layer "B.Cu")
		(at 394.13815 -110.25505 90)
		(property "Reference" "C2N7"
			(at 0 0 90)
			(layer "B.SilkS")
			(hide yes)
			(effects
				(font
					(size 1.27 1.27)
				)
				(justify mirror)
			)
		)
		(property "Value" ""
			(at 0 0 90)
			(layer "B.Fab")
			(effects
				(font
					(size 1.27 1.27)
				)
				(justify mirror)
			)
		)
		(duplicate_pad_numbers_are_jumpers no)
		(fp_rect
			(start 0.2794 0.9144)
			(end -0.2794 -0.1143)
			(stroke
				(width 0)
				(type default)
			)
			(fill no)
			(layer "B.CrtYd")
		)
		(fp_line
			(start 0.2794 -0.1143)
			(end -0.2794 -0.1143)
			(stroke
				(width 0.1)
				(type default)
			)
			(layer "B.Fab")
		)
		(fp_line
			(start -0.2794 -0.1143)
			(end -0.2794 0.9144)
			(stroke
				(width 0.1)
				(type default)
			)
			(layer "B.Fab")
		)
		(fp_line
			(start 0.2794 0.9144)
			(end 0.2794 -0.1143)
			(stroke
				(width 0.1)
				(type default)
			)
			(layer "B.Fab")
		)
		(fp_line
			(start -0.2794 0.9144)
			(end 0.2794 0.9144)
			(stroke
				(width 0.1)
				(type default)
			)
			(layer "B.Fab")
		)
		(pad "1" smd custom
			(at 0 0)
			(size 0.10414 0.10414)
			(layers "B.Cu" "B.Mask" "B.Paste")
			(net "P1V05_PCH_STBY")
			(options
				(clearance outline)
				(anchor circle)
			)
			(primitives
				(gr_poly
					(pts
						(xy -0.20828 -0.08636) (xy -0.20828 0.08636) (xy -0.08636 0.20828) (xy 0.086614 0.20828) (xy 0.20828 0.086614)
						(xy 0.20828 -0.08636) (xy 0.08636 -0.20828) (xy -0.08636 -0.20828)
					)
					(width 0)
					(fill yes)
				)
			)
		)
		(pad "2" smd custom
			(at 0 0.8001)
			(size 0.10414 0.10414)
			(layers "B.Cu" "B.Mask" "B.Paste")
			(net "GND")
			(options
				(clearance outline)
				(anchor circle)
			)
			(primitives
				(gr_poly
					(pts
						(xy -0.20828 -0.08636) (xy -0.20828 0.08636) (xy -0.08636 0.20828) (xy 0.086614 0.20828) (xy 0.20828 0.086614)
						(xy 0.20828 -0.08636) (xy 0.08636 -0.20828) (xy -0.08636 -0.20828)
					)
					(width 0)
					(fill yes)
				)
			)
		)
		(zone
			(layer "B.Cu")
			(hatch none 0.5)
			(connect_pads
				(clearance 0)
			)
			(min_thickness 0.25)
			(keepout
				(tracks not_allowed)
				(vias allowed)
				(pads allowed)
				(copperpour not_allowed)
				(footprints allowed)
			)
			(placement
				(enabled no)
				(sheetname "")
			)
			(fill
				(thermal_gap 0.5)
				(thermal_bridge_width 0.5)
				(island_removal_mode 0)
			)
			(polygon
				(pts
					(xy 394.3477 -110.34268) (xy 394.7287 -110.34268) (xy 394.7287 -110.16742) (xy 394.3477 -110.167166)
				)
			)
		)
		(zone
			(layer "B.Cu")
			(hatch none 0.5)
			(connect_pads
				(clearance 0)
			)
			(min_thickness 0.25)
			(keepout
				(tracks allowed)
				(vias not_allowed)
				(pads allowed)
				(copperpour not_allowed)
				(footprints allowed)
			)
			(placement
				(enabled no)
				(sheetname "")
			)
			(fill
				(thermal_gap 0.5)
				(thermal_bridge_width 0.5)
				(island_removal_mode 0)
			)
			(polygon
				(pts
					(xy 394.3477 -110.34268) (xy 394.7287 -110.34268) (xy 394.7287 -110.16742) (xy 394.3477 -110.167166)
				)
			)
		)
	)
	(footprint ""
		(layer "B.Cu")
		(at 358.3432 -4.2418 180)
		(property "Reference" "R8W12"
			(at 0.8382 -0.67818 180)
			(unlocked yes)
			(layer "B.SilkS")
			(effects
				(font
					(size 0.4064 0.254)
					(thickness 0.1524)
				)
				(justify left mirror)
			)
		)
		(property "Value" ""
			(at 0 0 0)
			(layer "B.Fab")
			(effects
				(font
					(size 1.27 1.27)
				)
				(justify mirror)
			)
		)
		(duplicate_pad_numbers_are_jumpers no)
		(fp_poly
			(pts
				(xy 0.2794 -0.1016) (xy -0.2794 -0.1016) (xy -0.2794 0.9906) (xy 0.2794 0.9906)
			)
			(stroke
				(width 0)
				(type default)
			)
			(fill no)
			(layer "B.CrtYd")
		)
		(fp_line
			(start 0.2794 0.9906)
			(end -0.2794 0.9906)
			(stroke
				(width 0.1)
				(type default)
			)
			(layer "B.Fab")
		)
		(fp_line
			(start 0.2794 -0.1016)
			(end 0.2794 0.9906)
			(stroke
				(width 0.1)
				(type default)
			)
			(layer "B.Fab")
		)
		(fp_line
			(start -0.2794 0.9906)
			(end -0.2794 -0.1016)
			(stroke
				(width 0.1)
				(type default)
			)
			(layer "B.Fab")
		)
		(fp_line
			(start -0.2794 -0.1016)
			(end 0.2794 -0.1016)
			(stroke
				(width 0.1)
				(type default)
			)
			(layer "B.Fab")
		)
		(pad "1" smd rect
			(at 0 0)
			(size 0.508 0.508)
			(layers "B.Cu" "B.Mask" "B.Paste")
			(net "JTAG_RISER_TRST")
		)
		(pad "2" smd rect
			(at 0 0.889)
			(size 0.508 0.508)
			(layers "B.Cu" "B.Mask" "B.Paste")
			(net "JTAG_BMC_TRST_N")
		)
		(zone
			(layer "B.Cu")
			(hatch none 0.5)
			(connect_pads
				(clearance 0)
			)
			(min_thickness 0.25)
			(keepout
				(tracks not_allowed)
				(vias allowed)
				(pads allowed)
				(copperpour not_allowed)
				(footprints allowed)
			)
			(placement
				(enabled no)
				(sheetname "")
			)
			(fill
				(thermal_gap 0.5)
				(thermal_bridge_width 0.5)
				(island_removal_mode 0)
			)
			(polygon
				(pts
					(xy 358.0892 -4.8768) (xy 358.5972 -4.8768) (xy 358.5972 -4.4958) (xy 358.0892 -4.4958)
				)
			)
		)
		(zone
			(layer "B.Cu")
			(hatch none 0.5)
			(connect_pads
				(clearance 0)
			)
			(min_thickness 0.25)
			(keepout
				(tracks allowed)
				(vias not_allowed)
				(pads allowed)
				(copperpour not_allowed)
				(footprints allowed)
			)
			(placement
				(enabled no)
				(sheetname "")
			)
			(fill
				(thermal_gap 0.5)
				(thermal_bridge_width 0.5)
				(island_removal_mode 0)
			)
			(polygon
				(pts
					(xy 358.0892 -4.4958) (xy 358.5972 -4.4958) (xy 358.5972 -4.8768) (xy 358.0892 -4.8768)
				)
			)
		)
	)
	(footprint ""
		(layer "B.Cu")
		(at 406.654 -94.474792 90)
		(property "Reference" "C8C3"
			(at 0 0 90)
			(layer "B.SilkS")
			(hide yes)
			(effects
				(font
					(size 1.27 1.27)
				)
				(justify mirror)
			)
		)
		(property "Value" ""
			(at 0 0 90)
			(layer "B.Fab")
			(effects
				(font
					(size 1.27 1.27)
				)
				(justify mirror)
			)
		)
		(duplicate_pad_numbers_are_jumpers no)
		(fp_poly
			(pts
				(xy 0.4953 -0.2032) (xy -0.4953 -0.2032) (xy -0.4953 1.6002) (xy 0.4953 1.6002)
			)
			(stroke
				(width 0)
				(type default)
			)
			(fill no)
			(layer "B.CrtYd")
		)
		(fp_line
			(start 0.4953 -0.2032)
			(end -0.4953 -0.2032)
			(stroke
				(width 0.1)
				(type default)
			)
			(layer "B.Fab")
		)
		(fp_line
			(start -0.4953 -0.2032)
			(end -0.4953 1.6002)
			(stroke
				(width 0.1)
				(type default)
			)
			(layer "B.Fab")
		)
		(fp_line
			(start 0.4953 1.6002)
			(end 0.4953 -0.2032)
			(stroke
				(width 0.1)
				(type default)
			)
			(layer "B.Fab")
		)
		(fp_line
			(start -0.4953 1.6002)
			(end 0.4953 1.6002)
			(stroke
				(width 0.1)
				(type default)
			)
			(layer "B.Fab")
		)
		(pad "1" smd rect
			(at 0 0 270)
			(size 0.762 0.889)
			(layers "B.Cu" "B.Mask" "B.Paste")
			(net "P3V3_STBY")
		)
		(pad "2" smd rect
			(at 0 1.397 270)
			(size 0.762 0.889)
			(layers "B.Cu" "B.Mask" "B.Paste")
			(net "GND")
		)
		(zone
			(layer "B.Cu")
			(hatch none 0.5)
			(connect_pads
				(clearance 0)
			)
			(min_thickness 0.25)
			(keepout
				(tracks not_allowed)
				(vias allowed)
				(pads allowed)
				(copperpour not_allowed)
				(footprints allowed)
			)
			(placement
				(enabled no)
				(sheetname "")
			)
			(fill
				(thermal_gap 0.5)
				(thermal_bridge_width 0.5)
				(island_removal_mode 0)
			)
			(polygon
				(pts
					(xy 407.0985 -94.855792) (xy 407.0985 -94.093792) (xy 407.6065 -94.093792) (xy 407.6065 -94.855792)
				)
			)
		)
	)
	(footprint ""
		(layer "B.Cu")
		(at 331.343 -155.829 180)
		(property "Reference" "R4L4"
			(at 0 0 0)
			(layer "B.SilkS")
			(hide yes)
			(effects
				(font
					(size 1.27 1.27)
				)
				(justify mirror)
			)
		)
		(property "Value" ""
			(at 0 0 0)
			(layer "B.Fab")
			(effects
				(font
					(size 1.27 1.27)
				)
				(justify mirror)
			)
		)
		(duplicate_pad_numbers_are_jumpers no)
		(fp_rect
			(start -0.4953 -0.2032)
			(end 0.4953 1.6002)
			(stroke
				(width 0)
				(type default)
			)
			(fill no)
			(layer "B.CrtYd")
		)
		(fp_line
			(start 0.4953 1.6002)
			(end 0.4953 -0.2032)
			(stroke
				(width 0.1)
				(type default)
			)
			(layer "B.Fab")
		)
		(fp_line
			(start 0.4953 -0.2032)
			(end -0.4953 -0.2032)
			(stroke
				(width 0.1)
				(type default)
			)
			(layer "B.Fab")
		)
		(fp_line
			(start -0.4953 1.6002)
			(end 0.4953 1.6002)
			(stroke
				(width 0.1)
				(type default)
			)
			(layer "B.Fab")
		)
		(fp_line
			(start -0.4953 -0.2032)
			(end -0.4953 1.6002)
			(stroke
				(width 0.1)
				(type default)
			)
			(layer "B.Fab")
		)
		(pad "1" smd rect
			(at 0 0)
			(size 0.762 0.889)
			(layers "B.Cu" "B.Mask" "B.Paste")
			(net "PVDDQ_DEF")
		)
		(pad "2" smd rect
			(at 0 1.397)
			(size 0.762 0.889)
			(layers "B.Cu" "B.Mask" "B.Paste")
			(net "GND")
		)
		(zone
			(layer "B.Cu")
			(hatch none 0.5)
			(connect_pads
				(clearance 0)
			)
			(min_thickness 0.25)
			(keepout
				(tracks not_allowed)
				(vias allowed)
				(pads allowed)
				(copperpour not_allowed)
				(footprints allowed)
			)
			(placement
				(enabled no)
				(sheetname "")
			)
			(fill
				(thermal_gap 0.5)
				(thermal_bridge_width 0.5)
				(island_removal_mode 0)
			)
			(polygon
				(pts
					(xy 331.724 -156.2735) (xy 331.724 -156.7815) (xy 330.962 -156.7815) (xy 330.962 -156.2735)
				)
			)
		)
		(zone
			(layer "B.Cu")
			(hatch none 0.5)
			(connect_pads
				(clearance 0)
			)
			(min_thickness 0.25)
			(keepout
				(tracks allowed)
				(vias not_allowed)
				(pads allowed)
				(copperpour not_allowed)
				(footprints allowed)
			)
			(placement
				(enabled no)
				(sheetname "")
			)
			(fill
				(thermal_gap 0.5)
				(thermal_bridge_width 0.5)
				(island_removal_mode 0)
			)
			(polygon
				(pts
					(xy 331.724 -156.2735) (xy 331.724 -156.7815) (xy 330.962 -156.7815) (xy 330.962 -156.2735)
				)
			)
		)
	)
	(footprint ""
		(layer "B.Cu")
		(at 340.741 -83.5914 90)
		(property "Reference" "R3P21"
			(at 0 0 90)
			(layer "B.SilkS")
			(hide yes)
			(effects
				(font
					(size 1.27 1.27)
				)
				(justify mirror)
			)
		)
		(property "Value" ""
			(at 0 0 90)
			(layer "B.Fab")
			(effects
				(font
					(size 1.27 1.27)
				)
				(justify mirror)
			)
		)
		(duplicate_pad_numbers_are_jumpers no)
		(fp_poly
			(pts
				(xy 0.2794 -0.1016) (xy -0.2794 -0.1016) (xy -0.2794 0.9906) (xy 0.2794 0.9906)
			)
			(stroke
				(width 0)
				(type default)
			)
			(fill no)
			(layer "B.CrtYd")
		)
		(fp_line
			(start 0.2794 -0.1016)
			(end 0.2794 0.9906)
			(stroke
				(width 0.1)
				(type default)
			)
			(layer "B.Fab")
		)
		(fp_line
			(start -0.2794 -0.1016)
			(end 0.2794 -0.1016)
			(stroke
				(width 0.1)
				(type default)
			)
			(layer "B.Fab")
		)
		(fp_line
			(start 0.2794 0.9906)
			(end -0.2794 0.9906)
			(stroke
				(width 0.1)
				(type default)
			)
			(layer "B.Fab")
		)
		(fp_line
			(start -0.2794 0.9906)
			(end -0.2794 -0.1016)
			(stroke
				(width 0.1)
				(type default)
			)
			(layer "B.Fab")
		)
		(pad "1" smd rect
			(at 0 0 270)
			(size 0.508 0.508)
			(layers "B.Cu" "B.Mask" "B.Paste")
			(net "P3V3_STBY")
		)
		(pad "2" smd rect
			(at 0 0.889 270)
			(size 0.508 0.508)
			(layers "B.Cu" "B.Mask" "B.Paste")
			(net "VR_PVCCIO_CPU0_EN")
		)
		(zone
			(layer "B.Cu")
			(hatch none 0.5)
			(connect_pads
				(clearance 0)
			)
			(min_thickness 0.25)
			(keepout
				(tracks allowed)
				(vias not_allowed)
				(pads allowed)
				(copperpour not_allowed)
				(footprints allowed)
			)
			(placement
				(enabled no)
				(sheetname "")
			)
			(fill
				(thermal_gap 0.5)
				(thermal_bridge_width 0.5)
				(island_removal_mode 0)
			)
			(polygon
				(pts
					(xy 340.995 -83.8454) (xy 340.995 -83.3374) (xy 341.376 -83.3374) (xy 341.376 -83.8454)
				)
			)
		)
		(zone
			(layer "B.Cu")
			(hatch none 0.5)
			(connect_pads
				(clearance 0)
			)
			(min_thickness 0.25)
			(keepout
				(tracks not_allowed)
				(vias allowed)
				(pads allowed)
				(copperpour not_allowed)
				(footprints allowed)
			)
			(placement
				(enabled no)
				(sheetname "")
			)
			(fill
				(thermal_gap 0.5)
				(thermal_bridge_width 0.5)
				(island_removal_mode 0)
			)
			(polygon
				(pts
					(xy 341.376 -83.8454) (xy 341.376 -83.3374) (xy 340.995 -83.3374) (xy 340.995 -83.8454)
				)
			)
		)
	)
	(footprint ""
		(layer "B.Cu")
		(at 31.0134 -72.1614 180)
		(property "Reference" "CTI7"
			(at 0.8382 -0.84963 180)
			(unlocked yes)
			(layer "B.SilkS")
			(effects
				(font
					(size 0.7874 0.5842)
					(thickness 0.1524)
				)
				(justify left mirror)
			)
		)
		(property "Value" ""
			(at 0 0 0)
			(layer "B.Fab")
			(effects
				(font
					(size 1.27 1.27)
				)
				(justify mirror)
			)
		)
		(duplicate_pad_numbers_are_jumpers no)
		(fp_poly
			(pts
				(xy -0.3048 -0.1016) (xy -0.3048 0.9906) (xy 0.3048 0.9906) (xy 0.3048 -0.1016)
			)
			(stroke
				(width 0)
				(type default)
			)
			(fill no)
			(layer "B.CrtYd")
		)
		(fp_line
			(start 0.3048 0.9906)
			(end -0.3048 0.9906)
			(stroke
				(width 0.1)
				(type default)
			)
			(layer "B.Fab")
		)
		(fp_line
			(start 0.3048 -0.1016)
			(end 0.3048 0.9906)
			(stroke
				(width 0.1)
				(type default)
			)
			(layer "B.Fab")
		)
		(fp_line
			(start -0.3048 0.9906)
			(end -0.3048 -0.1016)
			(stroke
				(width 0.1)
				(type default)
			)
			(layer "B.Fab")
		)
		(fp_line
			(start -0.3048 -0.1016)
			(end 0.3048 -0.1016)
			(stroke
				(width 0.1)
				(type default)
			)
			(layer "B.Fab")
		)
		(pad "1" smd rect
			(at 0 0)
			(size 0.508 0.508)
			(layers "B.Cu" "B.Mask" "B.Paste")
			(net "A_TSENSE_PVCCIN_CPU1")
		)
		(pad "2" smd rect
			(at 0 0.889)
			(size 0.508 0.508)
			(layers "B.Cu" "B.Mask" "B.Paste")
			(net "GND")
		)
		(zone
			(layer "B.Cu")
			(hatch none 0.5)
			(connect_pads
				(clearance 0)
			)
			(min_thickness 0.25)
			(keepout
				(tracks not_allowed)
				(vias allowed)
				(pads allowed)
				(copperpour not_allowed)
				(footprints allowed)
			)
			(placement
				(enabled no)
				(sheetname "")
			)
			(fill
				(thermal_gap 0.5)
				(thermal_bridge_width 0.5)
				(island_removal_mode 0)
			)
			(polygon
				(pts
					(xy 30.7594 -72.7964) (xy 31.2674 -72.7964) (xy 31.2674 -72.4154) (xy 30.7594 -72.4154)
				)
			)
		)
		(zone
			(layer "B.Cu")
			(hatch none 0.5)
			(connect_pads
				(clearance 0)
			)
			(min_thickness 0.25)
			(keepout
				(tracks allowed)
				(vias not_allowed)
				(pads allowed)
				(copperpour not_allowed)
				(footprints allowed)
			)
			(placement
				(enabled no)
				(sheetname "")
			)
			(fill
				(thermal_gap 0.5)
				(thermal_bridge_width 0.5)
				(island_removal_mode 0)
			)
			(polygon
				(pts
					(xy 30.7594 -72.4154) (xy 31.2674 -72.4154) (xy 31.2674 -72.7964) (xy 30.7594 -72.7964)
				)
			)
		)
	)
)
